# S9S_MB_2U (Grand Teton) — schematic netlist excerpt (pin names and nets, part order shuffled) for the footprints in the layout excerpt that follows; sources: Cadence DE-HDL packaged netlist, KiCad conversion of 03242023_DA0F0TMBIJ0_F0T_Motherboard_J_brd_V01_OCP.brd

R1266  Q_RES  75 1% CHIP  pkg 0402LF  page 203 : A = P1V05_PCH_AUX ; B = H_THERMTRIP_LVC1_N
R3142  Q_RES  0 5% CHIP  pkg 0402LF  page 162 : A = HP_LVC3_OCP_V3_2_PRSNT2_N_R ; B = HP_LVC3_OCP_V3_2_PRSNT2_N

(kicad_pcb
	(version 20260206)
	(generator "pcbnew")
	(generator_version "10.0")
	(general
		(thickness 1.6)
		(legacy_teardrops no)
	)
	(paper "A4")
	(title_block
		(title "03242023_DA0F0TMBIJ0_F0T_Motherboard_J_brd_V01_OCP.brd")
		(comment 1 "Grand Teton / footprints 3194-3195 of 6105")
	)
	(layers
		(0 "F.Cu" signal "TOP")
		(4 "In1.Cu" signal "GND")
		(6 "In2.Cu" signal "IN1")
		(8 "In3.Cu" signal "GND1")
		(10 "In4.Cu" signal "IN2")
		(12 "In5.Cu" signal "GND2")
		(14 "In6.Cu" signal "IN3")
		(16 "In7.Cu" signal "GND3")
		(18 "In8.Cu" signal "VCC")
		(20 "In9.Cu" signal "VCC1")
		(22 "In10.Cu" signal "GND4")
		(24 "In11.Cu" signal "IN4")
		(26 "In12.Cu" signal "GND5")
		(28 "In13.Cu" signal "IN5")
		(30 "In14.Cu" signal "GND6")
		(32 "In15.Cu" signal "IN6")
		(34 "In16.Cu" signal "GND7")
		(2 "B.Cu" signal "BOTTOM")
		(9 "F.Adhes" user "F.Adhesive")
		(11 "B.Adhes" user "B.Adhesive")
		(13 "F.Paste" user "Package Geometry/Pastemask Top")
		(15 "B.Paste" user "Package Geometry/Pastemask Bottom")
		(5 "F.SilkS" user "Ref Des/Silkscreen Top")
		(7 "B.SilkS" user "Ref Des/Silkscreen Bottom")
		(1 "F.Mask" user "Board Geometry/Soldermask Top")
		(3 "B.Mask" user "Board Geometry/Soldermask Bottom")
		(17 "Dwgs.User" user "User.Drawings")
		(19 "Cmts.User" user "User.Comments")
		(21 "Eco1.User" user "User.Eco1")
		(23 "Eco2.User" user "User.Eco2")
		(25 "Edge.Cuts" user "Board Geometry/Outline")
		(27 "Margin" user)
		(31 "F.CrtYd" user "Package Geometry/Place Bound Top")
		(29 "B.CrtYd" user "Package Geometry/Place Bound Bottom")
		(35 "F.Fab" user "Ref Des/Assembly Top")
		(33 "B.Fab" user "Ref Des/Assembly Bottom")
	)
	(footprint ""
		(layer "F.Cu")
		(at 28.578048 -70.83425)
		(property "Reference" "R3142"
			(at 0 0 0)
			(layer "F.SilkS")
			(hide yes)
			(effects
				(font
					(size 1.27 1.27)
				)
			)
		)
		(property "Value" ""
			(at 0 0 0)
			(layer "F.Fab")
			(effects
				(font
					(size 1.27 1.27)
				)
			)
		)
		(duplicate_pad_numbers_are_jumpers no)
		(fp_line
			(start -0.7874 -0.4064)
			(end 0.7874 -0.4064)
			(stroke
				(width 0.1524)
				(type default)
			)
			(layer "F.SilkS")
		)
		(fp_line
			(start -0.7874 0.4064)
			(end -0.7874 -0.4064)
			(stroke
				(width 0.1524)
				(type default)
			)
			(layer "F.SilkS")
		)
		(fp_line
			(start 0.7874 -0.4064)
			(end 0.7874 0.4064)
			(stroke
				(width 0.1524)
				(type default)
			)
			(layer "F.SilkS")
		)
		(fp_line
			(start 0.7874 0.4064)
			(end -0.7874 0.4064)
			(stroke
				(width 0.1524)
				(type default)
			)
			(layer "F.SilkS")
		)
		(fp_line
			(start -0.67945 -0.305054)
			(end -0.12065 -0.305054)
			(stroke
				(width 0.1)
				(type default)
			)
			(layer "F.Fab")
		)
		(fp_line
			(start -0.67945 0.3048)
			(end -0.67945 -0.305054)
			(stroke
				(width 0.1)
				(type default)
			)
			(layer "F.Fab")
		)
		(fp_line
			(start -0.12065 -0.305054)
			(end -0.12065 -0.2794)
			(stroke
				(width 0.1)
				(type default)
			)
			(layer "F.Fab")
		)
		(fp_line
			(start -0.12065 -0.2794)
			(end 0.12065 -0.2794)
			(stroke
				(width 0.1)
				(type default)
			)
			(layer "F.Fab")
		)
		(fp_line
			(start -0.12065 0.2794)
			(end -0.12065 0.3048)
			(stroke
				(width 0.1)
				(type default)
			)
			(layer "F.Fab")
		)
		(fp_line
			(start -0.12065 0.3048)
			(end -0.67945 0.3048)
			(stroke
				(width 0.1)
				(type default)
			)
			(layer "F.Fab")
		)
		(fp_line
			(start 0.120396 0.2794)
			(end -0.12065 0.2794)
			(stroke
				(width 0.1)
				(type default)
			)
			(layer "F.Fab")
		)
		(fp_line
			(start 0.120396 0.3048)
			(end 0.120396 0.2794)
			(stroke
				(width 0.1)
				(type default)
			)
			(layer "F.Fab")
		)
		(fp_line
			(start 0.12065 -0.3048)
			(end 0.67945 -0.3048)
			(stroke
				(width 0.1)
				(type default)
			)
			(layer "F.Fab")
		)
		(fp_line
			(start 0.12065 -0.2794)
			(end 0.12065 -0.3048)
			(stroke
				(width 0.1)
				(type default)
			)
			(layer "F.Fab")
		)
		(fp_line
			(start 0.67945 -0.3048)
			(end 0.67945 0.3048)
			(stroke
				(width 0.1)
				(type default)
			)
			(layer "F.Fab")
		)
		(fp_line
			(start 0.67945 0.3048)
			(end 0.120396 0.3048)
			(stroke
				(width 0.1)
				(type default)
			)
			(layer "F.Fab")
		)
		(pad "1" smd circle
			(at -0.40005 0)
			(size 0 0)
			(layers "F.Cu" "F.Mask" "F.Paste")
			(net "HP_LVC3_OCP_V3_2_PRSNT2_N_R")
		)
		(pad "2" smd circle
			(at 0.40005 0)
			(size 0 0)
			(layers "F.Cu" "F.Mask" "F.Paste")
			(net "HP_LVC3_OCP_V3_2_PRSNT2_N")
		)
	)
	(footprint ""
		(layer "F.Cu")
		(at 317.418212 -62.342268)
		(property "Reference" "R1266"
			(at 0 0 0)
			(layer "F.SilkS")
			(hide yes)
			(effects
				(font
					(size 1.27 1.27)
				)
			)
		)
		(property "Value" ""
			(at 0 0 0)
			(layer "F.Fab")
			(effects
				(font
					(size 1.27 1.27)
				)
			)
		)
		(duplicate_pad_numbers_are_jumpers no)
		(fp_line
			(start -0.7874 -0.4064)
			(end 0.7874 -0.4064)
			(stroke
				(width 0.1524)
				(type default)
			)
			(layer "F.SilkS")
		)
		(fp_line
			(start -0.7874 0.4064)
			(end -0.7874 -0.4064)
			(stroke
				(width 0.1524)
				(type default)
			)
			(layer "F.SilkS")
		)
		(fp_line
			(start 0.7874 -0.4064)
			(end 0.7874 0.4064)
			(stroke
				(width 0.1524)
				(type default)
			)
			(layer "F.SilkS")
		)
		(fp_line
			(start 0.7874 0.4064)
			(end -0.7874 0.4064)
			(stroke
				(width 0.1524)
				(type default)
			)
			(layer "F.SilkS")
		)
		(fp_line
			(start -0.67945 -0.305054)
			(end -0.12065 -0.305054)
			(stroke
				(width 0.1)
				(type default)
			)
			(layer "F.Fab")
		)
		(fp_line
			(start -0.67945 0.3048)
			(end -0.67945 -0.305054)
			(stroke
				(width 0.1)
				(type default)
			)
			(layer "F.Fab")
		)
		(fp_line
			(start -0.12065 -0.305054)
			(end -0.12065 -0.2794)
			(stroke
				(width 0.1)
				(type default)
			)
			(layer "F.Fab")
		)
		(fp_line
			(start -0.12065 -0.2794)
			(end 0.12065 -0.2794)
			(stroke
				(width 0.1)
				(type default)
			)
			(layer "F.Fab")
		)
		(fp_line
			(start -0.12065 0.2794)
			(end -0.12065 0.3048)
			(stroke
				(width 0.1)
				(type default)
			)
			(layer "F.Fab")
		)
		(fp_line
			(start -0.12065 0.3048)
			(end -0.67945 0.3048)
			(stroke
				(width 0.1)
				(type default)
			)
			(layer "F.Fab")
		)
		(fp_line
			(start 0.120396 0.2794)
			(end -0.12065 0.2794)
			(stroke
				(width 0.1)
				(type default)
			)
			(layer "F.Fab")
		)
		(fp_line
			(start 0.120396 0.3048)
			(end 0.120396 0.2794)
			(stroke
				(width 0.1)
				(type default)
			)
			(layer "F.Fab")
		)
		(fp_line
			(start 0.12065 -0.3048)
			(end 0.67945 -0.3048)
			(stroke
				(width 0.1)
				(type default)
			)
			(layer "F.Fab")
		)
		(fp_line
			(start 0.12065 -0.2794)
			(end 0.12065 -0.3048)
			(stroke
				(width 0.1)
				(type default)
			)
			(layer "F.Fab")
		)
		(fp_line
			(start 0.67945 -0.3048)
			(end 0.67945 0.3048)
			(stroke
				(width 0.1)
				(type default)
			)
			(layer "F.Fab")
		)
		(fp_line
			(start 0.67945 0.3048)
			(end 0.120396 0.3048)
			(stroke
				(width 0.1)
				(type default)
			)
			(layer "F.Fab")
		)
		(pad "1" smd circle
			(at -0.40005 0)
			(size 0 0)
			(layers "F.Cu" "F.Mask" "F.Paste")
			(net "P1V05_PCH_AUX")
		)
		(pad "2" smd circle
			(at 0.40005 0)
			(size 0 0)
			(layers "F.Cu" "F.Mask" "F.Paste")
			(net "H_THERMTRIP_LVC1_N")
		)
	)
)
